# SCM (Grand Teton) — schematic netlist excerpt (pin names and nets, part order shuffled) for the footprints in the layout excerpt that follows; sources: Cadence DE-HDL packaged netlist, KiCad conversion of 12092022_DA0F0TMDCD0_F0T_Management_Board_D_brd_V3_OCP.brd

R818  Q_RES  100K 1% EMPTY  pkg 0402LF  page 12 : A = SMB_BMC_MM13_R_SDA ; B = GND

Q8  2N7002A7  2N7002A-7 IC  pkg SOT23_GDSXC  page 28
  D  = FM_SOL_UART_CH_SEL_R3
  G  = FM_UART_SEL_N
  S  = GND

(kicad_pcb
	(version 20260206)
	(generator "pcbnew")
	(generator_version "10.0")
	(general
		(thickness 1.6)
		(legacy_teardrops no)
	)
	(paper "A4")
	(title_block
		(title "12092022_DA0F0TMDCD0_F0T_Management_Board_D_brd_V3_OCP.brd")
		(comment 1 "Grand Teton / footprints 1043-1044 of 1440")
	)
	(layers
		(0 "F.Cu" signal "TOP")
		(4 "In1.Cu" signal "GND")
		(6 "In2.Cu" signal "IN1")
		(8 "In3.Cu" signal "GND1")
		(10 "In4.Cu" signal "IN2")
		(12 "In5.Cu" signal "VCC")
		(14 "In6.Cu" signal "VCC1")
		(16 "In7.Cu" signal "IN3")
		(18 "In8.Cu" signal "GND2")
		(20 "In9.Cu" signal "IN4")
		(22 "In10.Cu" signal "GND3")
		(2 "B.Cu" signal "BOTTOM")
		(9 "F.Adhes" user "F.Adhesive")
		(11 "B.Adhes" user "B.Adhesive")
		(13 "F.Paste" user "Package Geometry/Pastemask Top")
		(15 "B.Paste" user "Package Geometry/Pastemask Bottom")
		(5 "F.SilkS" user "Ref Des/Silkscreen Top")
		(7 "B.SilkS" user "Ref Des/Silkscreen Bottom")
		(1 "F.Mask" user "Board Geometry/Soldermask Top")
		(3 "B.Mask" user "Board Geometry/Soldermask Bottom")
		(17 "Dwgs.User" user "User.Drawings")
		(19 "Cmts.User" user "User.Comments")
		(21 "Eco1.User" user "User.Eco1")
		(23 "Eco2.User" user "User.Eco2")
		(25 "Edge.Cuts" user "Board Geometry/Outline")
		(27 "Margin" user)
		(31 "F.CrtYd" user "Package Geometry/Place Bound Top")
		(29 "B.CrtYd" user "Package Geometry/Place Bound Bottom")
		(35 "F.Fab" user "Ref Des/Assembly Top")
		(33 "B.Fab" user "Ref Des/Assembly Bottom")
	)
	(footprint ""
		(layer "B.Cu")
		(at 41.966134 -47.231808)
		(property "Reference" "R818"
			(at 0 0 0)
			(layer "B.SilkS")
			(hide yes)
			(effects
				(font
					(size 1.27 1.27)
				)
				(justify mirror)
			)
		)
		(property "Value" ""
			(at 0 0 0)
			(layer "B.Fab")
			(effects
				(font
					(size 1.27 1.27)
				)
				(justify mirror)
			)
		)
		(duplicate_pad_numbers_are_jumpers no)
		(fp_line
			(start -0.7874 -0.4064)
			(end -0.7874 0.4064)
			(stroke
				(width 0.1524)
				(type default)
			)
			(layer "B.SilkS")
		)
		(fp_line
			(start -0.7874 0.4064)
			(end 0.7874 0.4064)
			(stroke
				(width 0.1524)
				(type default)
			)
			(layer "B.SilkS")
		)
		(fp_line
			(start 0.7874 -0.4064)
			(end -0.7874 -0.4064)
			(stroke
				(width 0.1524)
				(type default)
			)
			(layer "B.SilkS")
		)
		(fp_line
			(start 0.7874 0.4064)
			(end 0.7874 -0.4064)
			(stroke
				(width 0.1524)
				(type default)
			)
			(layer "B.SilkS")
		)
		(fp_line
			(start -0.67945 -0.3048)
			(end -0.67945 0.3048)
			(stroke
				(width 0.1)
				(type default)
			)
			(layer "B.Fab")
		)
		(fp_line
			(start -0.67945 0.3048)
			(end -0.120396 0.3048)
			(stroke
				(width 0.1)
				(type default)
			)
			(layer "B.Fab")
		)
		(fp_line
			(start -0.12065 -0.3048)
			(end -0.67945 -0.3048)
			(stroke
				(width 0.1)
				(type default)
			)
			(layer "B.Fab")
		)
		(fp_line
			(start -0.12065 -0.2794)
			(end -0.12065 -0.3048)
			(stroke
				(width 0.1)
				(type default)
			)
			(layer "B.Fab")
		)
		(fp_line
			(start -0.120396 0.2794)
			(end 0.12065 0.2794)
			(stroke
				(width 0.1)
				(type default)
			)
			(layer "B.Fab")
		)
		(fp_line
			(start -0.120396 0.3048)
			(end -0.120396 0.2794)
			(stroke
				(width 0.1)
				(type default)
			)
			(layer "B.Fab")
		)
		(fp_line
			(start 0.12065 -0.305054)
			(end 0.12065 -0.2794)
			(stroke
				(width 0.1)
				(type default)
			)
			(layer "B.Fab")
		)
		(fp_line
			(start 0.12065 -0.2794)
			(end -0.12065 -0.2794)
			(stroke
				(width 0.1)
				(type default)
			)
			(layer "B.Fab")
		)
		(fp_line
			(start 0.12065 0.2794)
			(end 0.12065 0.3048)
			(stroke
				(width 0.1)
				(type default)
			)
			(layer "B.Fab")
		)
		(fp_line
			(start 0.12065 0.3048)
			(end 0.67945 0.3048)
			(stroke
				(width 0.1)
				(type default)
			)
			(layer "B.Fab")
		)
		(fp_line
			(start 0.67945 -0.305054)
			(end 0.12065 -0.305054)
			(stroke
				(width 0.1)
				(type default)
			)
			(layer "B.Fab")
		)
		(fp_line
			(start 0.67945 0.3048)
			(end 0.67945 -0.305054)
			(stroke
				(width 0.1)
				(type default)
			)
			(layer "B.Fab")
		)
		(pad "1" smd circle
			(at 0.40005 0 180)
			(size 0 0)
			(layers "B.Cu" "B.Mask" "B.Paste")
			(net "SMB_BMC_MM13_R_SDA")
		)
		(pad "2" smd circle
			(at -0.40005 0 180)
			(size 0 0)
			(layers "B.Cu" "B.Mask" "B.Paste")
			(net "GND")
		)
	)
	(footprint ""
		(layer "B.Cu")
		(at 59.436 -99.06 180)
		(property "Reference" "Q8"
			(at 2.3622 1.10363 0)
			(unlocked yes)
			(layer "B.SilkS")
			(effects
				(font
					(size 0.7874 0.5842)
					(thickness 0.1524)
				)
				(justify left mirror)
			)
		)
		(property "Value" ""
			(at 0 0 0)
			(layer "B.Fab")
			(effects
				(font
					(size 1.27 1.27)
				)
				(justify mirror)
			)
		)
		(duplicate_pad_numbers_are_jumpers no)
		(fp_line
			(start 1.603248 1.500124)
			(end 1.603248 -1.500124)
			(stroke
				(width 0.1524)
				(type default)
			)
			(layer "B.SilkS")
		)
		(fp_line
			(start 1.603248 -1.500124)
			(end -1.603248 -1.500124)
			(stroke
				(width 0.1524)
				(type default)
			)
			(layer "B.SilkS")
		)
		(fp_line
			(start -1.603248 1.500124)
			(end 1.603248 1.500124)
			(stroke
				(width 0.1524)
				(type default)
			)
			(layer "B.SilkS")
		)
		(fp_line
			(start -1.603248 -1.500124)
			(end -1.603248 1.500124)
			(stroke
				(width 0.1524)
				(type default)
			)
			(layer "B.SilkS")
		)
		(fp_line
			(start 1.249934 1.169924)
			(end 0.700024 1.169924)
			(stroke
				(width 0.1)
				(type default)
			)
			(layer "B.Fab")
		)
		(fp_line
			(start 1.249934 0.729996)
			(end 1.249934 1.169924)
			(stroke
				(width 0.1)
				(type default)
			)
			(layer "B.Fab")
		)
		(fp_line
			(start 1.249934 -0.729996)
			(end 0.6985 -0.729996)
			(stroke
				(width 0.1)
				(type default)
			)
			(layer "B.Fab")
		)
		(fp_line
			(start 1.249934 -1.169924)
			(end 1.249934 -0.729996)
			(stroke
				(width 0.1)
				(type default)
			)
			(layer "B.Fab")
		)
		(fp_line
			(start 0.700024 1.500124)
			(end -0.700024 1.500124)
			(stroke
				(width 0.1)
				(type default)
			)
			(layer "B.Fab")
		)
		(fp_line
			(start 0.700024 1.169924)
			(end 0.700024 1.500124)
			(stroke
				(width 0.1)
				(type default)
			)
			(layer "B.Fab")
		)
		(fp_line
			(start 0.700024 -1.169924)
			(end 1.249934 -1.169924)
			(stroke
				(width 0.1)
				(type default)
			)
			(layer "B.Fab")
		)
		(fp_line
			(start 0.700024 -1.500124)
			(end 0.700024 -1.169924)
			(stroke
				(width 0.1)
				(type default)
			)
			(layer "B.Fab")
		)
		(fp_line
			(start 0.6985 0.729996)
			(end 1.249934 0.729996)
			(stroke
				(width 0.1)
				(type default)
			)
			(layer "B.Fab")
		)
		(fp_line
			(start 0.6985 -0.729996)
			(end 0.6985 0.729996)
			(stroke
				(width 0.1)
				(type default)
			)
			(layer "B.Fab")
		)
		(fp_line
			(start -0.700024 1.500124)
			(end -0.700024 0.219964)
			(stroke
				(width 0.1)
				(type default)
			)
			(layer "B.Fab")
		)
		(fp_line
			(start -0.700024 0.219964)
			(end -1.249934 0.219964)
			(stroke
				(width 0.1)
				(type default)
			)
			(layer "B.Fab")
		)
		(fp_line
			(start -0.700024 -0.219964)
			(end -0.700024 -1.500124)
			(stroke
				(width 0.1)
				(type default)
			)
			(layer "B.Fab")
		)
		(fp_line
			(start -0.700024 -1.500124)
			(end 0.700024 -1.500124)
			(stroke
				(width 0.1)
				(type default)
			)
			(layer "B.Fab")
		)
		(fp_line
			(start -1.249934 0.219964)
			(end -1.249934 -0.219964)
			(stroke
				(width 0.1)
				(type default)
			)
			(layer "B.Fab")
		)
		(fp_line
			(start -1.249934 -0.219964)
			(end -0.700024 -0.219964)
			(stroke
				(width 0.1)
				(type default)
			)
			(layer "B.Fab")
		)
		(fp_rect
			(start 0.700024 1.500124)
			(end -0.700024 -1.500124)
			(stroke
				(width 0)
				(type default)
			)
			(fill no)
			(layer "B.Fab")
		)
		(pad "D" smd rect
			(at -0.999998 0 90)
			(size 0.8128 0.9144)
			(layers "B.Cu" "B.Mask" "B.Paste")
			(net "FM_SOL_UART_CH_SEL_R3")
		)
		(pad "G" smd rect
			(at 0.999998 -0.94996 90)
			(size 0.8128 0.9144)
			(layers "B.Cu" "B.Mask" "B.Paste")
			(net "FM_UART_SEL_N")
		)
		(pad "S" smd rect
			(at 0.999998 0.94996 90)
			(size 0.8128 0.9144)
			(layers "B.Cu" "B.Mask" "B.Paste")
			(net "GND")
		)
	)
)
